(kicad_pcb
	(version 20260206)
	(generator "pcbnew")
	(generator_version "10.0")
	(general
		(thickness 1.6)
		(legacy_teardrops no)
	)
	(paper "A4")
	(title_block
		(title "4HDD Backplane_Layout.brd")
		(comment 1 "Tioga Pass / footprints 57-64 of 97")
	)
	(layers
		(0 "F.Cu" signal "TOP")
		(4 "In1.Cu" signal "L2GND")
		(6 "In2.Cu" signal "L3")
		(8 "In3.Cu" signal "L4")
		(10 "In4.Cu" signal "L5GND")
		(2 "B.Cu" signal "BOTTOM")
		(9 "F.Adhes" user "F.Adhesive")
		(11 "B.Adhes" user "B.Adhesive")
		(13 "F.Paste" user "Package Geometry/Pastemask Top")
		(15 "B.Paste" user "Package Geometry/Pastemask Bottom")
		(5 "F.SilkS" user "Ref Des/Silkscreen Top")
		(7 "B.SilkS" user "Ref Des/Silkscreen Bottom")
		(1 "F.Mask" user "Board Geometry/Soldermask Top")
		(3 "B.Mask" user "Board Geometry/Soldermask Bottom")
		(17 "Dwgs.User" user "User.Drawings")
		(19 "Cmts.User" user "User.Comments")
		(21 "Eco1.User" user "User.Eco1")
		(23 "Eco2.User" user "User.Eco2")
		(25 "Edge.Cuts" user "Board Geometry/Outline")
		(27 "Margin" user)
		(31 "F.CrtYd" user "Package Geometry/Place Bound Top")
		(29 "B.CrtYd" user "Package Geometry/Place Bound Bottom")
		(35 "F.Fab" user "Ref Des/Assembly Top")
		(33 "B.Fab" user "Ref Des/Assembly Bottom")
	)
	(footprint ""
		(layer "F.Cu")
		(at 86.566248 -11.259058 -90)
		(property "Reference" "R163"
			(at 0 0 270)
			(layer "F.SilkS")
			(hide yes)
			(effects
				(font
					(size 1.27 1.27)
				)
			)
		)
		(property "Value" "0R5J-5-GP"
			(at 0 -8.9535 270)
			(unlocked yes)
			(layer "F.Fab")
			(hide yes)
			(effects
				(font
					(size 1.27 1.016)
					(thickness 0.1524)
				)
			)
		)
		(property "Device Type" "R805H24"
			(at 0 -10.6299 270)
			(unlocked yes)
			(layer "F.Fab")
			(hide yes)
			(effects
				(font
					(size 1.27 1.016)
					(thickness 0.1524)
				)
			)
		)
		(duplicate_pad_numbers_are_jumpers no)
		(fp_line
			(start -0.889 1.7018)
			(end 0.889 1.7018)
			(stroke
				(width 0.1524)
				(type default)
			)
			(layer "F.SilkS")
		)
		(fp_line
			(start 0.889 1.7018)
			(end 0.889 -0.508)
			(stroke
				(width 0.1524)
				(type default)
			)
			(layer "F.SilkS")
		)
		(fp_line
			(start -0.889 0.0762)
			(end -0.889 1.7018)
			(stroke
				(width 0.1524)
				(type default)
			)
			(layer "F.SilkS")
		)
		(fp_line
			(start -0.889 -1.7018)
			(end -0.889 0.2794)
			(stroke
				(width 0.1524)
				(type default)
			)
			(layer "F.SilkS")
		)
		(fp_line
			(start 0.889 -1.7018)
			(end 0.889 -0.381)
			(stroke
				(width 0.1524)
				(type default)
			)
			(layer "F.SilkS")
		)
		(fp_line
			(start 0.889 -1.7018)
			(end -0.889 -1.7018)
			(stroke
				(width 0.1524)
				(type default)
			)
			(layer "F.SilkS")
		)
		(fp_poly
			(pts
				(xy 0.9652 -1.778) (xy 0.9652 1.778) (xy -0.9652 1.778) (xy -0.9652 -1.778)
			)
			(stroke
				(width 0)
				(type default)
			)
			(fill no)
			(layer "F.CrtYd")
		)
		(fp_rect
			(start -0.9652 1.778)
			(end 0.9652 -1.778)
			(stroke
				(width 0)
				(type default)
			)
			(fill no)
			(layer "F.Fab")
		)
		(pad "1" smd rect
			(at 0 -0.9652 270)
			(size 1.397 1.143)
			(layers "F.Cu" "F.Mask" "F.Paste")
			(net "P12V")
		)
		(pad "2" smd rect
			(at 0 0.9652 270)
			(size 1.397 1.143)
			(layers "F.Cu" "F.Mask" "F.Paste")
			(net "P12V_SW_L")
		)
	)
	(footprint ""
		(layer "F.Cu")
		(at 77.724 -52.324 -90)
		(property "Reference" "C6"
			(at 0 0 270)
			(layer "F.SilkS")
			(hide yes)
			(effects
				(font
					(size 1.27 1.27)
				)
			)
		)
		(property "Value" "SCD1U25V2KX-GP"
			(at 1.1811 -2.7051 270)
			(unlocked yes)
			(layer "F.Fab")
			(hide yes)
			(effects
				(font
					(size 1.016 1.016)
					(thickness 0.1524)
				)
			)
		)
		(property "Device Type" "C402H22"
			(at 1.1811 -4.2291 270)
			(unlocked yes)
			(layer "F.Fab")
			(hide yes)
			(effects
				(font
					(size 1.016 1.016)
					(thickness 0.1524)
				)
			)
		)
		(duplicate_pad_numbers_are_jumpers no)
		(fp_rect
			(start -0.4318 0.9525)
			(end 0.4318 -0.9525)
			(stroke
				(width 0)
				(type default)
			)
			(fill no)
			(layer "F.CrtYd")
		)
		(fp_rect
			(start -0.4318 0.9525)
			(end 0.4318 -0.9525)
			(stroke
				(width 0)
				(type default)
			)
			(fill no)
			(layer "F.Fab")
		)
		(pad "1" smd custom
			(at 0 -0.4445 270)
			(size 0.1524 0.1524)
			(layers "F.Cu" "F.Mask" "F.Paste")
			(net "P5V_SW_R")
			(options
				(clearance outline)
				(anchor circle)
			)
			(primitives
				(gr_poly
					(pts
						(arc
							(start 0.3048 -0.2032)
							(mid 0.275042 -0.275042)
							(end 0.2032 -0.3048)
						)
						(arc
							(start -0.2032 -0.3048)
							(mid -0.275042 -0.275042)
							(end -0.3048 -0.2032)
						)
						(arc
							(start -0.3048 0.2032)
							(mid -0.275042 0.275042)
							(end -0.2032 0.3048)
						)
						(arc
							(start 0.2032 0.3048)
							(mid 0.275042 0.275042)
							(end 0.3048 0.2032)
						)
					)
					(width 0)
					(fill yes)
				)
			)
		)
		(pad "2" smd custom
			(at 0 0.4445 270)
			(size 0.1524 0.1524)
			(layers "F.Cu" "F.Mask" "F.Paste")
			(net "GND")
			(options
				(clearance outline)
				(anchor circle)
			)
			(primitives
				(gr_poly
					(pts
						(arc
							(start 0.3048 -0.2032)
							(mid 0.275042 -0.275042)
							(end 0.2032 -0.3048)
						)
						(arc
							(start -0.2032 -0.3048)
							(mid -0.275042 -0.275042)
							(end -0.3048 -0.2032)
						)
						(arc
							(start -0.3048 0.2032)
							(mid -0.275042 0.275042)
							(end -0.2032 0.3048)
						)
						(arc
							(start 0.2032 0.3048)
							(mid 0.275042 0.275042)
							(end 0.3048 0.2032)
						)
					)
					(width 0)
					(fill yes)
				)
			)
		)
	)
	(footprint ""
		(layer "F.Cu")
		(at 127.728472 -40.966644 180)
		(property "Reference" "C1"
			(at 0 0 180)
			(layer "F.SilkS")
			(hide yes)
			(effects
				(font
					(size 1.27 1.27)
				)
			)
		)
		(property "Value" "SCD01U50V2KX-1GP"
			(at 1.1811 -2.7051 180)
			(unlocked yes)
			(layer "F.Fab")
			(hide yes)
			(effects
				(font
					(size 1.016 1.016)
					(thickness 0.1524)
				)
			)
		)
		(property "Device Type" "C402H22"
			(at 1.1811 -4.2291 180)
			(unlocked yes)
			(layer "F.Fab")
			(hide yes)
			(effects
				(font
					(size 1.016 1.016)
					(thickness 0.1524)
				)
			)
		)
		(duplicate_pad_numbers_are_jumpers no)
		(fp_rect
			(start -0.4318 0.9525)
			(end 0.4318 -0.9525)
			(stroke
				(width 0)
				(type default)
			)
			(fill no)
			(layer "F.CrtYd")
		)
		(fp_rect
			(start -0.4318 0.9525)
			(end 0.4318 -0.9525)
			(stroke
				(width 0)
				(type default)
			)
			(fill no)
			(layer "F.Fab")
		)
		(pad "1" smd custom
			(at 0 -0.4445 180)
			(size 0.1524 0.1524)
			(layers "F.Cu" "F.Mask" "F.Paste")
			(net "HBA_PRSNT1_N")
			(options
				(clearance outline)
				(anchor circle)
			)
			(primitives
				(gr_poly
					(pts
						(arc
							(start 0.3048 -0.2032)
							(mid 0.275042 -0.275042)
							(end 0.2032 -0.3048)
						)
						(arc
							(start -0.2032 -0.3048)
							(mid -0.275042 -0.275042)
							(end -0.3048 -0.2032)
						)
						(arc
							(start -0.3048 0.2032)
							(mid -0.275042 0.275042)
							(end -0.2032 0.3048)
						)
						(arc
							(start 0.2032 0.3048)
							(mid 0.275042 0.275042)
							(end 0.3048 0.2032)
						)
					)
					(width 0)
					(fill yes)
				)
			)
		)
		(pad "2" smd custom
			(at 0 0.4445 180)
			(size 0.1524 0.1524)
			(layers "F.Cu" "F.Mask" "F.Paste")
			(net "GND")
			(options
				(clearance outline)
				(anchor circle)
			)
			(primitives
				(gr_poly
					(pts
						(arc
							(start 0.3048 -0.2032)
							(mid 0.275042 -0.275042)
							(end 0.2032 -0.3048)
						)
						(arc
							(start -0.2032 -0.3048)
							(mid -0.275042 -0.275042)
							(end -0.3048 -0.2032)
						)
						(arc
							(start -0.3048 0.2032)
							(mid -0.275042 0.275042)
							(end -0.2032 0.3048)
						)
						(arc
							(start 0.2032 0.3048)
							(mid 0.275042 0.275042)
							(end 0.3048 0.2032)
						)
					)
					(width 0)
					(fill yes)
				)
			)
		)
	)
	(footprint ""
		(layer "F.Cu")
		(at 81.153 -36.068 90)
		(property "Reference" "R137"
			(at 0 0 90)
			(layer "F.SilkS")
			(hide yes)
			(effects
				(font
					(size 1.27 1.27)
				)
			)
		)
		(property "Value" "4K7R2J-2-GP"
			(at 0.064008 -3.993896 90)
			(unlocked yes)
			(layer "F.Fab")
			(hide yes)
			(effects
				(font
					(size 1.016 1.016)
					(thickness 0.1524)
				)
			)
		)
		(property "Device Type" "R402H16"
			(at 0.064008 -5.517896 90)
			(unlocked yes)
			(layer "F.Fab")
			(hide yes)
			(effects
				(font
					(size 1.016 1.016)
					(thickness 0.1524)
				)
			)
		)
		(duplicate_pad_numbers_are_jumpers no)
		(fp_line
			(start 0.508 -0.9398)
			(end -0.508 -0.9398)
			(stroke
				(width 0.1524)
				(type default)
			)
			(layer "F.SilkS")
		)
		(fp_line
			(start -0.508 -0.9398)
			(end -0.508 0.9398)
			(stroke
				(width 0.1524)
				(type default)
			)
			(layer "F.SilkS")
		)
		(fp_rect
			(start -0.508 0.9398)
			(end 0.508 -0.9398)
			(stroke
				(width 0)
				(type default)
			)
			(fill no)
			(layer "F.CrtYd")
		)
		(fp_rect
			(start -0.508 0.9398)
			(end 0.508 -0.9398)
			(stroke
				(width 0)
				(type default)
			)
			(fill no)
			(layer "F.Fab")
		)
		(pad "1" smd custom
			(at 0 -0.4445 90)
			(size 0.1397 0.1397)
			(layers "F.Cu" "F.Mask" "F.Paste")
			(net "P12V")
			(options
				(clearance outline)
				(anchor circle)
			)
			(primitives
				(gr_poly
					(pts
						(arc
							(start -0.1778 -0.2794)
							(mid -0.249642 -0.249642)
							(end -0.2794 -0.1778)
						)
						(arc
							(start -0.2794 0.1778)
							(mid -0.249642 0.249642)
							(end -0.1778 0.2794)
						)
						(arc
							(start 0.1778 0.2794)
							(mid 0.249642 0.249642)
							(end 0.2794 0.1778)
						)
						(arc
							(start 0.2794 -0.1778)
							(mid 0.249642 -0.249642)
							(end 0.1778 -0.2794)
						)
					)
					(width 0)
					(fill yes)
				)
			)
		)
		(pad "2" smd custom
			(at 0 0.4445 90)
			(size 0.1397 0.1397)
			(layers "F.Cu" "F.Mask" "F.Paste")
			(net "SW_SW_R_0")
			(options
				(clearance outline)
				(anchor circle)
			)
			(primitives
				(gr_poly
					(pts
						(arc
							(start -0.1778 -0.2794)
							(mid -0.249642 -0.249642)
							(end -0.2794 -0.1778)
						)
						(arc
							(start -0.2794 0.1778)
							(mid -0.249642 0.249642)
							(end -0.1778 0.2794)
						)
						(arc
							(start 0.1778 0.2794)
							(mid 0.249642 0.249642)
							(end 0.2794 0.1778)
						)
						(arc
							(start 0.2794 -0.1778)
							(mid 0.249642 -0.249642)
							(end 0.1778 -0.2794)
						)
					)
					(width 0)
					(fill yes)
				)
			)
		)
	)
	(footprint ""
		(layer "F.Cu")
		(at 53.6194 -8.5852 180)
		(property "Reference" "C14"
			(at 0 0 180)
			(layer "F.SilkS")
			(hide yes)
			(effects
				(font
					(size 1.27 1.27)
				)
			)
		)
		(property "Value" "SCD01U50V2KX-1GP"
			(at 1.1811 -2.7051 180)
			(unlocked yes)
			(layer "F.Fab")
			(hide yes)
			(effects
				(font
					(size 1.016 1.016)
					(thickness 0.1524)
				)
			)
		)
		(property "Device Type" "C402H22"
			(at 1.1811 -4.2291 180)
			(unlocked yes)
			(layer "F.Fab")
			(hide yes)
			(effects
				(font
					(size 1.016 1.016)
					(thickness 0.1524)
				)
			)
		)
		(duplicate_pad_numbers_are_jumpers no)
		(fp_rect
			(start -0.4318 0.9525)
			(end 0.4318 -0.9525)
			(stroke
				(width 0)
				(type default)
			)
			(fill no)
			(layer "F.CrtYd")
		)
		(fp_rect
			(start -0.4318 0.9525)
			(end 0.4318 -0.9525)
			(stroke
				(width 0)
				(type default)
			)
			(fill no)
			(layer "F.Fab")
		)
		(pad "1" smd custom
			(at 0 -0.4445 180)
			(size 0.1524 0.1524)
			(layers "F.Cu" "F.Mask" "F.Paste")
			(net "HBA_PRSNT3_N")
			(options
				(clearance outline)
				(anchor circle)
			)
			(primitives
				(gr_poly
					(pts
						(arc
							(start 0.3048 -0.2032)
							(mid 0.275042 -0.275042)
							(end 0.2032 -0.3048)
						)
						(arc
							(start -0.2032 -0.3048)
							(mid -0.275042 -0.275042)
							(end -0.3048 -0.2032)
						)
						(arc
							(start -0.3048 0.2032)
							(mid -0.275042 0.275042)
							(end -0.2032 0.3048)
						)
						(arc
							(start 0.2032 0.3048)
							(mid 0.275042 0.275042)
							(end 0.3048 0.2032)
						)
					)
					(width 0)
					(fill yes)
				)
			)
		)
		(pad "2" smd custom
			(at 0 0.4445 180)
			(size 0.1524 0.1524)
			(layers "F.Cu" "F.Mask" "F.Paste")
			(net "GND")
			(options
				(clearance outline)
				(anchor circle)
			)
			(primitives
				(gr_poly
					(pts
						(arc
							(start 0.3048 -0.2032)
							(mid 0.275042 -0.275042)
							(end 0.2032 -0.3048)
						)
						(arc
							(start -0.2032 -0.3048)
							(mid -0.275042 -0.275042)
							(end -0.3048 -0.2032)
						)
						(arc
							(start -0.3048 0.2032)
							(mid -0.275042 0.275042)
							(end -0.2032 0.3048)
						)
						(arc
							(start 0.2032 0.3048)
							(mid 0.275042 0.275042)
							(end 0.3048 0.2032)
						)
					)
					(width 0)
					(fill yes)
				)
			)
		)
	)
	(footprint ""
		(layer "F.Cu")
		(at 90.678 -10.033 180)
		(property "Reference" "R148"
			(at 0 0 180)
			(layer "F.SilkS")
			(hide yes)
			(effects
				(font
					(size 1.27 1.27)
				)
			)
		)
		(property "Value" "300KR2F-GP"
			(at 0.064008 -3.993896 180)
			(unlocked yes)
			(layer "F.Fab")
			(hide yes)
			(effects
				(font
					(size 1.016 1.016)
					(thickness 0.1524)
				)
			)
		)
		(property "Device Type" "R402H16"
			(at 0.064008 -5.517896 180)
			(unlocked yes)
			(layer "F.Fab")
			(hide yes)
			(effects
				(font
					(size 1.016 1.016)
					(thickness 0.1524)
				)
			)
		)
		(duplicate_pad_numbers_are_jumpers no)
		(fp_line
			(start 0.508 -0.9398)
			(end -0.508 -0.9398)
			(stroke
				(width 0.1524)
				(type default)
			)
			(layer "F.SilkS")
		)
		(fp_line
			(start -0.508 -0.9398)
			(end -0.508 0.9398)
			(stroke
				(width 0.1524)
				(type default)
			)
			(layer "F.SilkS")
		)
		(fp_rect
			(start -0.508 0.9398)
			(end 0.508 -0.9398)
			(stroke
				(width 0)
				(type default)
			)
			(fill no)
			(layer "F.CrtYd")
		)
		(fp_rect
			(start -0.508 0.9398)
			(end 0.508 -0.9398)
			(stroke
				(width 0)
				(type default)
			)
			(fill no)
			(layer "F.Fab")
		)
		(pad "1" smd custom
			(at 0 -0.4445 180)
			(size 0.1397 0.1397)
			(layers "F.Cu" "F.Mask" "F.Paste")
			(net "SW_SW_L_N_0")
			(options
				(clearance outline)
				(anchor circle)
			)
			(primitives
				(gr_poly
					(pts
						(arc
							(start -0.1778 -0.2794)
							(mid -0.249642 -0.249642)
							(end -0.2794 -0.1778)
						)
						(arc
							(start -0.2794 0.1778)
							(mid -0.249642 0.249642)
							(end -0.1778 0.2794)
						)
						(arc
							(start 0.1778 0.2794)
							(mid 0.249642 0.249642)
							(end 0.2794 0.1778)
						)
						(arc
							(start 0.2794 -0.1778)
							(mid 0.249642 -0.249642)
							(end 0.1778 -0.2794)
						)
					)
					(width 0)
					(fill yes)
				)
			)
		)
		(pad "2" smd custom
			(at 0 0.4445 180)
			(size 0.1397 0.1397)
			(layers "F.Cu" "F.Mask" "F.Paste")
			(net "P12V")
			(options
				(clearance outline)
				(anchor circle)
			)
			(primitives
				(gr_poly
					(pts
						(arc
							(start -0.1778 -0.2794)
							(mid -0.249642 -0.249642)
							(end -0.2794 -0.1778)
						)
						(arc
							(start -0.2794 0.1778)
							(mid -0.249642 0.249642)
							(end -0.1778 0.2794)
						)
						(arc
							(start 0.1778 0.2794)
							(mid 0.249642 0.249642)
							(end 0.2794 0.1778)
						)
						(arc
							(start 0.2794 -0.1778)
							(mid 0.249642 -0.249642)
							(end 0.1778 -0.2794)
						)
					)
					(width 0)
					(fill yes)
				)
			)
		)
	)
	(footprint ""
		(layer "F.Cu")
		(at 56.82488 -8.609838 -90)
		(property "Reference" "R11"
			(at 0 0 270)
			(layer "F.SilkS")
			(hide yes)
			(effects
				(font
					(size 1.27 1.27)
				)
			)
		)
		(property "Value" "10R3F-GP"
			(at -0.0254 -2.5146 270)
			(unlocked yes)
			(layer "F.Fab")
			(hide yes)
			(effects
				(font
					(size 1.016 1.016)
					(thickness 0.1524)
				)
			)
		)
		(property "Device Type" "R603H22"
			(at -0.0254 -4.0386 270)
			(unlocked yes)
			(layer "F.Fab")
			(hide yes)
			(effects
				(font
					(size 1.016 1.016)
					(thickness 0.1524)
				)
			)
		)
		(duplicate_pad_numbers_are_jumpers no)
		(fp_line
			(start -0.4826 0)
			(end -0.2032 0)
			(stroke
				(width 0.2032)
				(type default)
			)
			(layer "F.SilkS")
		)
		(fp_line
			(start 0.2032 0)
			(end 0.4826 0)
			(stroke
				(width 0.2032)
				(type default)
			)
			(layer "F.SilkS")
		)
		(fp_rect
			(start -0.5842 1.3335)
			(end 0.5842 -1.3335)
			(stroke
				(width 0)
				(type default)
			)
			(fill no)
			(layer "F.CrtYd")
		)
		(fp_rect
			(start -0.5842 1.3335)
			(end 0.5842 -1.3335)
			(stroke
				(width 0)
				(type default)
			)
			(fill no)
			(layer "F.Fab")
		)
		(pad "1" smd custom
			(at 0 -0.762 270)
			(size 0.2159 0.2159)
			(layers "F.Cu" "F.Mask" "F.Paste")
			(net "P12V_SW_L")
			(options
				(clearance outline)
				(anchor circle)
			)
			(primitives
				(gr_poly
					(pts
						(arc
							(start -0.3302 -0.4318)
							(mid -0.402042 -0.402042)
							(end -0.4318 -0.3302)
						)
						(arc
							(start -0.4318 0.3302)
							(mid -0.402042 0.402042)
							(end -0.3302 0.4318)
						)
						(arc
							(start 0.3302 0.4318)
							(mid 0.402042 0.402042)
							(end 0.4318 0.3302)
						)
						(arc
							(start 0.4318 -0.3302)
							(mid 0.402042 -0.402042)
							(end 0.3302 -0.4318)
						)
					)
					(width 0)
					(fill yes)
				)
			)
		)
		(pad "2" smd custom
			(at 0 0.762 270)
			(size 0.2159 0.2159)
			(layers "F.Cu" "F.Mask" "F.Paste")
			(net "12V_PRE_3")
			(options
				(clearance outline)
				(anchor circle)
			)
			(primitives
				(gr_poly
					(pts
						(arc
							(start -0.3302 -0.4318)
							(mid -0.402042 -0.402042)
							(end -0.4318 -0.3302)
						)
						(arc
							(start -0.4318 0.3302)
							(mid -0.402042 0.402042)
							(end -0.3302 0.4318)
						)
						(arc
							(start 0.3302 0.4318)
							(mid 0.402042 0.402042)
							(end 0.4318 0.3302)
						)
						(arc
							(start 0.4318 -0.3302)
							(mid 0.402042 -0.402042)
							(end 0.3302 -0.4318)
						)
					)
					(width 0)
					(fill yes)
				)
			)
		)
	)
	(footprint ""
		(layer "F.Cu")
		(at 68.603368 -12.333986 -90)
		(property "Reference" "R166"
			(at 0 0 270)
			(layer "F.SilkS")
			(hide yes)
			(effects
				(font
					(size 1.27 1.27)
				)
			)
		)
		(property "Value" "0R5J-5-GP"
			(at 0 -8.9535 270)
			(unlocked yes)
			(layer "F.Fab")
			(hide yes)
			(effects
				(font
					(size 1.27 1.016)
					(thickness 0.1524)
				)
			)
		)
		(property "Device Type" "R805H24"
			(at 0 -10.6299 270)
			(unlocked yes)
			(layer "F.Fab")
			(hide yes)
			(effects
				(font
					(size 1.27 1.016)
					(thickness 0.1524)
				)
			)
		)
		(duplicate_pad_numbers_are_jumpers no)
		(fp_line
			(start -0.889 1.7018)
			(end 0.889 1.7018)
			(stroke
				(width 0.1524)
				(type default)
			)
			(layer "F.SilkS")
		)
		(fp_line
			(start 0.889 1.7018)
			(end 0.889 -0.508)
			(stroke
				(width 0.1524)
				(type default)
			)
			(layer "F.SilkS")
		)
		(fp_line
			(start -0.889 0.0762)
			(end -0.889 1.7018)
			(stroke
				(width 0.1524)
				(type default)
			)
			(layer "F.SilkS")
		)
		(fp_line
			(start -0.889 -1.7018)
			(end -0.889 0.2794)
			(stroke
				(width 0.1524)
				(type default)
			)
			(layer "F.SilkS")
		)
		(fp_line
			(start 0.889 -1.7018)
			(end 0.889 -0.381)
			(stroke
				(width 0.1524)
				(type default)
			)
			(layer "F.SilkS")
		)
		(fp_line
			(start 0.889 -1.7018)
			(end -0.889 -1.7018)
			(stroke
				(width 0.1524)
				(type default)
			)
			(layer "F.SilkS")
		)
		(fp_poly
			(pts
				(xy 0.9652 -1.778) (xy 0.9652 1.778) (xy -0.9652 1.778) (xy -0.9652 -1.778)
			)
			(stroke
				(width 0)
				(type default)
			)
			(fill no)
			(layer "F.CrtYd")
		)
		(fp_rect
			(start -0.9652 1.778)
			(end 0.9652 -1.778)
			(stroke
				(width 0)
				(type default)
			)
			(fill no)
			(layer "F.Fab")
		)
		(pad "1" smd rect
			(at 0 -0.9652 270)
			(size 1.397 1.143)
			(layers "F.Cu" "F.Mask" "F.Paste")
			(net "P5V")
		)
		(pad "2" smd rect
			(at 0 0.9652 270)
			(size 1.397 1.143)
			(layers "F.Cu" "F.Mask" "F.Paste")
			(net "P5V_SW_L")
		)
	)
)
